;LEADER: 12 
;HEADER: 
;CODE  : ASCII 
;FILE  : 9324_DA0F0TMBIJ0_F0T_Motherboard_J_v01_20230324_0910-bd-1-13.drl for backdrilling ... from layer TOP to layer GND5
;DESIGN: 9324_DA0F0TMBIJ0_F0T_Motherboard_J_v01_20230324_0910.brd
;MUST-NOT-CUT-LAYER = IN5,  MAX_DRILL_DEPTH = 72.25 MILS,  MFG_STUB_LENGTH = 0.00 MILS
;   BackdrillSize 1. = 17.700000 Tolerance = +0.000000/-0.000000 NON_PLATED MILS Quantity = 8
%
G90
X1032433Y-0033211
X1032433Y-0029811
X1341752Y-0033211
X1341752Y-0029811
X1290291Y-0033211
X1290291Y-0029811
X1482650Y-0033211
X1482650Y-0029811
M30
